# T6G (Grand Teton) — schematic netlist excerpt (pin names and nets, part order shuffled) for the footprints in the layout excerpt that follows; sources: Cadence DE-HDL packaged netlist, KiCad conversion of 04192023_DAF0TMB3IC0_F0TG_MB_C_brd_V02_OCP.brd

C2336  Q_CAP  22UF 4V 20% X6S  pkg C0402  page 73 : A = PVDDCR_CPU0_P1 ; B = GND

U3  SN74LVC1G07DBVR  IC  pkg SMLF  page 29
  NC  = NC
  A  = SCM_USB_OC_N
  GND  = GND
  Y  = SCM_USB_OC_BU_R_N
  VCC  = P1V8_AUX

(kicad_pcb
	(version 20260206)
	(generator "pcbnew")
	(generator_version "10.0")
	(general
		(thickness 1.6)
		(legacy_teardrops no)
	)
	(paper "A4")
	(title_block
		(title "04192023_DAF0TMB3IC0_F0TG_MB_C_brd_V02_OCP.brd")
		(comment 1 "Grand Teton / footprints 7701-7702 of 8354")
	)
	(layers
		(0 "F.Cu" signal "TOP")
		(4 "In1.Cu" signal "GND")
		(6 "In2.Cu" signal "IN1")
		(8 "In3.Cu" signal "GND1")
		(10 "In4.Cu" signal "IN2")
		(12 "In5.Cu" signal "GND2")
		(14 "In6.Cu" signal "IN3")
		(16 "In7.Cu" signal "GND3")
		(18 "In8.Cu" signal "VCC")
		(20 "In9.Cu" signal "VCC1")
		(22 "In10.Cu" signal "GND4")
		(24 "In11.Cu" signal "IN4")
		(26 "In12.Cu" signal "GND5")
		(28 "In13.Cu" signal "IN5")
		(30 "In14.Cu" signal "GND6")
		(32 "In15.Cu" signal "IN6")
		(34 "In16.Cu" signal "GND7")
		(2 "B.Cu" signal "BOTTOM")
		(9 "F.Adhes" user "F.Adhesive")
		(11 "B.Adhes" user "B.Adhesive")
		(13 "F.Paste" user "Package Geometry/Pastemask Top")
		(15 "B.Paste" user "Package Geometry/Pastemask Bottom")
		(5 "F.SilkS" user "Ref Des/Silkscreen Top")
		(7 "B.SilkS" user "Ref Des/Silkscreen Bottom")
		(1 "F.Mask" user "Board Geometry/Soldermask Top")
		(3 "B.Mask" user "Board Geometry/Soldermask Bottom")
		(17 "Dwgs.User" user "User.Drawings")
		(19 "Cmts.User" user "User.Comments")
		(21 "Eco1.User" user "User.Eco1")
		(23 "Eco2.User" user "User.Eco2")
		(25 "Edge.Cuts" user "Board Geometry/Outline")
		(27 "Margin" user)
		(31 "F.CrtYd" user "Package Geometry/Place Bound Top")
		(29 "B.CrtYd" user "Package Geometry/Place Bound Bottom")
		(35 "F.Fab" user "Ref Des/Assembly Top")
		(33 "B.Fab" user "Ref Des/Assembly Bottom")
	)
	(footprint ""
		(layer "B.Cu")
		(at 123.766834 -245.868952 -90)
		(property "Reference" "C2336"
			(at 0 0 90)
			(layer "B.SilkS")
			(hide yes)
			(effects
				(font
					(size 1.27 1.27)
				)
				(justify mirror)
			)
		)
		(property "Value" ""
			(at 0 0 90)
			(layer "B.Fab")
			(effects
				(font
					(size 1.27 1.27)
				)
				(justify mirror)
			)
		)
		(duplicate_pad_numbers_are_jumpers no)
		(fp_line
			(start -0.7874 0.4064)
			(end 0.7874 0.4064)
			(stroke
				(width 0.1524)
				(type default)
			)
			(layer "B.SilkS")
		)
		(fp_line
			(start 0.7874 0.4064)
			(end 0.7874 -0.4064)
			(stroke
				(width 0.1524)
				(type default)
			)
			(layer "B.SilkS")
		)
		(fp_line
			(start -0.7874 -0.4064)
			(end -0.7874 0.4064)
			(stroke
				(width 0.1524)
				(type default)
			)
			(layer "B.SilkS")
		)
		(fp_line
			(start 0.7874 -0.4064)
			(end -0.7874 -0.4064)
			(stroke
				(width 0.1524)
				(type default)
			)
			(layer "B.SilkS")
		)
		(fp_line
			(start -0.67945 0.3048)
			(end -0.120396 0.3048)
			(stroke
				(width 0.1)
				(type default)
			)
			(layer "B.Fab")
		)
		(fp_line
			(start -0.120396 0.3048)
			(end -0.120396 0.2794)
			(stroke
				(width 0.1)
				(type default)
			)
			(layer "B.Fab")
		)
		(fp_line
			(start 0.12065 0.3048)
			(end 0.67945 0.3048)
			(stroke
				(width 0.1)
				(type default)
			)
			(layer "B.Fab")
		)
		(fp_line
			(start 0.67945 0.3048)
			(end 0.67945 -0.305054)
			(stroke
				(width 0.1)
				(type default)
			)
			(layer "B.Fab")
		)
		(fp_line
			(start -0.120396 0.2794)
			(end 0.12065 0.2794)
			(stroke
				(width 0.1)
				(type default)
			)
			(layer "B.Fab")
		)
		(fp_line
			(start 0.12065 0.2794)
			(end 0.12065 0.3048)
			(stroke
				(width 0.1)
				(type default)
			)
			(layer "B.Fab")
		)
		(fp_line
			(start -0.12065 -0.2794)
			(end -0.12065 -0.3048)
			(stroke
				(width 0.1)
				(type default)
			)
			(layer "B.Fab")
		)
		(fp_line
			(start 0.12065 -0.2794)
			(end -0.12065 -0.2794)
			(stroke
				(width 0.1)
				(type default)
			)
			(layer "B.Fab")
		)
		(fp_line
			(start -0.67945 -0.3048)
			(end -0.67945 0.3048)
			(stroke
				(width 0.1)
				(type default)
			)
			(layer "B.Fab")
		)
		(fp_line
			(start -0.12065 -0.3048)
			(end -0.67945 -0.3048)
			(stroke
				(width 0.1)
				(type default)
			)
			(layer "B.Fab")
		)
		(fp_line
			(start 0.12065 -0.305054)
			(end 0.12065 -0.2794)
			(stroke
				(width 0.1)
				(type default)
			)
			(layer "B.Fab")
		)
		(fp_line
			(start 0.67945 -0.305054)
			(end 0.12065 -0.305054)
			(stroke
				(width 0.1)
				(type default)
			)
			(layer "B.Fab")
		)
		(pad "1" smd circle
			(at 0.40005 0 90)
			(size 0 0)
			(layers "B.Cu" "B.Mask" "B.Paste")
			(net "PVDDCR_CPU0_P1")
		)
		(pad "2" smd circle
			(at -0.40005 0 90)
			(size 0 0)
			(layers "B.Cu" "B.Mask" "B.Paste")
			(net "GND")
		)
	)
	(footprint ""
		(layer "B.Cu")
		(at 402.42617 -202.500484)
		(property "Reference" "U3"
			(at 2.032 -2.377948 0)
			(unlocked yes)
			(layer "B.SilkS")
			(effects
				(font
					(size 0.7874 0.5842)
					(thickness 0.1524)
				)
				(justify left mirror)
			)
		)
		(property "Value" ""
			(at 0 0 0)
			(layer "B.Fab")
			(effects
				(font
					(size 1.27 1.27)
				)
				(justify mirror)
			)
		)
		(duplicate_pad_numbers_are_jumpers no)
		(fp_line
			(start -2.0574 -1.651)
			(end -2.0574 1.651)
			(stroke
				(width 0.1524)
				(type default)
			)
			(layer "B.SilkS")
		)
		(fp_line
			(start -2.0574 1.651)
			(end 2.0574 1.651)
			(stroke
				(width 0.1524)
				(type default)
			)
			(layer "B.SilkS")
		)
		(fp_line
			(start -0.381 -1.651)
			(end -2.0574 -1.651)
			(stroke
				(width 0.1524)
				(type default)
			)
			(layer "B.SilkS")
		)
		(fp_line
			(start 0 -1.016)
			(end -0.381 -1.651)
			(stroke
				(width 0.1524)
				(type default)
			)
			(layer "B.SilkS")
		)
		(fp_line
			(start 0.381 -1.651)
			(end 0 -1.016)
			(stroke
				(width 0.1524)
				(type default)
			)
			(layer "B.SilkS")
		)
		(fp_line
			(start 2.0574 -1.651)
			(end 0.381 -1.651)
			(stroke
				(width 0.1524)
				(type default)
			)
			(layer "B.SilkS")
		)
		(fp_line
			(start 2.0574 1.651)
			(end 2.0574 -1.651)
			(stroke
				(width 0.1524)
				(type default)
			)
			(layer "B.SilkS")
		)
		(fp_poly
			(pts
				(xy 2.159 -1.016) (xy 2.71272 -1.344168) (xy 2.71272 -0.719328)
			)
			(stroke
				(width 0)
				(type default)
			)
			(fill yes)
			(layer "B.SilkS")
		)
		(fp_line
			(start -1.599946 -1.199896)
			(end -1.599946 1.199896)
			(stroke
				(width 0.1)
				(type default)
			)
			(layer "B.Fab")
		)
		(fp_line
			(start -1.599946 1.199896)
			(end -0.899922 1.199896)
			(stroke
				(width 0.1)
				(type default)
			)
			(layer "B.Fab")
		)
		(fp_line
			(start -0.899922 -1.549908)
			(end -0.899922 -1.199896)
			(stroke
				(width 0.1)
				(type default)
			)
			(layer "B.Fab")
		)
		(fp_line
			(start -0.899922 -1.199896)
			(end -1.599946 -1.199896)
			(stroke
				(width 0.1)
				(type default)
			)
			(layer "B.Fab")
		)
		(fp_line
			(start -0.899922 1.199896)
			(end -0.899922 1.549908)
			(stroke
				(width 0.1)
				(type default)
			)
			(layer "B.Fab")
		)
		(fp_line
			(start -0.899922 1.549908)
			(end 0.899922 1.549908)
			(stroke
				(width 0.1)
				(type default)
			)
			(layer "B.Fab")
		)
		(fp_line
			(start 0.899922 -1.549908)
			(end -0.899922 -1.549908)
			(stroke
				(width 0.1)
				(type default)
			)
			(layer "B.Fab")
		)
		(fp_line
			(start 0.899922 -1.199896)
			(end 0.899922 -1.549908)
			(stroke
				(width 0.1)
				(type default)
			)
			(layer "B.Fab")
		)
		(fp_line
			(start 0.899922 1.199896)
			(end 1.599946 1.199896)
			(stroke
				(width 0.1)
				(type default)
			)
			(layer "B.Fab")
		)
		(fp_line
			(start 0.899922 1.549908)
			(end 0.899922 1.199896)
			(stroke
				(width 0.1)
				(type default)
			)
			(layer "B.Fab")
		)
		(fp_line
			(start 1.599946 -1.199896)
			(end 0.899922 -1.199896)
			(stroke
				(width 0.1)
				(type default)
			)
			(layer "B.Fab")
		)
		(fp_line
			(start 1.599946 1.199896)
			(end 1.599946 -1.199896)
			(stroke
				(width 0.1)
				(type default)
			)
			(layer "B.Fab")
		)
		(fp_poly
			(pts
				(xy 2.71272 -0.719328) (xy 2.71272 -1.344168) (xy 2.159 -1.016)
			)
			(stroke
				(width 0)
				(type default)
			)
			(fill yes)
			(layer "B.Fab")
		)
		(pad "1" smd rect
			(at 1.225042 -0.94996 270)
			(size 0.5588 1.3462)
			(layers "B.Cu" "B.Mask" "B.Paste")
			(net "Net_10733")
		)
		(pad "2" smd rect
			(at 1.225042 0 270)
			(size 0.5588 1.3462)
			(layers "B.Cu" "B.Mask" "B.Paste")
			(net "SCM_USB_OC_N")
		)
		(pad "3" smd rect
			(at 1.225042 0.94996 270)
			(size 0.5588 1.3462)
			(layers "B.Cu" "B.Mask" "B.Paste")
			(net "GND")
		)
		(pad "4" smd rect
			(at -1.225042 0.94996 270)
			(size 0.5588 1.3462)
			(layers "B.Cu" "B.Mask" "B.Paste")
			(net "SCM_USB_OC_BU_R_N")
		)
		(pad "5" smd rect
			(at -1.225042 -0.94996 270)
			(size 0.5588 1.3462)
			(layers "B.Cu" "B.Mask" "B.Paste")
			(net "P1V8_AUX")
		)
	)
)
